(kicad_pcb
	(version 20241229)
	(generator "pcbnew")
	(generator_version "9.0")
	(general
		(thickness 1.294)
		(legacy_teardrops no)
	)
	(paper "A3")
	(title_block
		(title "Kintex 410T devboard")
		(date "2024-04-03")
		(rev "1.1.2")
		(comment 9 "footprints 725-730 of 975")
	)
	(layers
		(0 "F.Cu" mixed)
		(4 "In1.Cu" power)
		(6 "In2.Cu" power)
		(8 "In3.Cu" mixed)
		(10 "In4.Cu" power)
		(12 "In5.Cu" mixed)
		(14 "In6.Cu" power)
		(16 "In7.Cu" mixed)
		(18 "In8.Cu" power)
		(2 "B.Cu" mixed)
		(9 "F.Adhes" user "F.Adhesive")
		(11 "B.Adhes" user "B.Adhesive")
		(13 "F.Paste" user)
		(15 "B.Paste" user)
		(5 "F.SilkS" user "F.Silkscreen")
		(7 "B.SilkS" user "B.Silkscreen")
		(1 "F.Mask" user)
		(3 "B.Mask" user)
		(17 "Dwgs.User" user "User.Drawings")
		(19 "Cmts.User" user "User.Comments")
		(21 "Eco1.User" user "User.Eco1")
		(23 "Eco2.User" user "User.Eco2")
		(25 "Edge.Cuts" user)
		(27 "Margin" user)
		(31 "F.CrtYd" user "F.Courtyard")
		(29 "B.CrtYd" user "B.Courtyard")
		(35 "F.Fab" user)
		(33 "B.Fab" user)
	)
	(footprint "antmicro-footprints:C_0402_1005Metric"
		(layer "B.Cu")
		(at 187.5 142 90)
		(descr "Capacitor SMD 0402")
		(tags "capacitor SMD 0402")
		(property "Reference" "C71"
			(at 1.075 -0.425 270)
			(layer "B.SilkS")
			(effects
				(font
					(size 0.7 0.7)
					(thickness 0.15)
				)
				(justify left bottom mirror)
			)
		)
		(property "Value" "C_100n_0402"
			(at 0 -1.169 270)
			(layer "B.Fab")
			(effects
				(font
					(size 0.7 0.7)
					(thickness 0.15)
				)
				(justify left bottom mirror)
			)
		)
		(property "Description" "SMD Multilayer Ceramic Capacitor, 0.1 µF, 50 V, 0402 [1005 Metric], ± 10%, X5R, GRM Series"
			(at 0 0 90)
			(layer "F.Fab")
			(hide yes)
			(effects
				(font
					(size 1.27 1.27)
					(thickness 0.15)
				)
			)
		)
		(property "Author" "Antmicro"
			(at 329.5 -45.5 0)
			(layer "B.Fab")
			(hide yes)
			(effects
				(font
					(size 1 1)
					(thickness 0.15)
				)
				(justify mirror)
			)
		)
		(property "Dielectric" "X5R"
			(at 329.5 -45.5 0)
			(layer "B.Fab")
			(hide yes)
			(effects
				(font
					(size 1 1)
					(thickness 0.15)
				)
				(justify mirror)
			)
		)
		(property "License" "Apache-2.0"
			(at 329.5 -45.5 0)
			(layer "B.Fab")
			(hide yes)
			(effects
				(font
					(size 1 1)
					(thickness 0.15)
				)
				(justify mirror)
			)
		)
		(property "MPN" "GRM155R61H104KE14D"
			(at 329.5 -45.5 0)
			(layer "B.Fab")
			(hide yes)
			(effects
				(font
					(size 1 1)
					(thickness 0.15)
				)
				(justify mirror)
			)
		)
		(property "Manufacturer" "Murata"
			(at 329.5 -45.5 0)
			(layer "B.Fab")
			(hide yes)
			(effects
				(font
					(size 1 1)
					(thickness 0.15)
				)
				(justify mirror)
			)
		)
		(property "Val" "100n"
			(at 329.5 -45.5 0)
			(layer "B.Fab")
			(hide yes)
			(effects
				(font
					(size 1 1)
					(thickness 0.15)
				)
				(justify mirror)
			)
		)
		(property "Voltage" "50V"
			(at 329.5 -45.5 0)
			(layer "B.Fab")
			(hide yes)
			(effects
				(font
					(size 1 1)
					(thickness 0.15)
				)
				(justify mirror)
			)
		)
		(sheetname "FPGA Bank 33 & 34")
		(sheetfile "fpga-bank-33-34.kicad_sch")
		(attr smd)
		(fp_rect
			(start -0.925 0.47)
			(end 0.925 -0.47)
			(stroke
				(width 0.05)
				(type default)
			)
			(fill no)
			(layer "B.CrtYd")
		)
		(fp_line
			(start 0.504 -0.248)
			(end -0.494 -0.248)
			(stroke
				(width 0.15)
				(type solid)
			)
			(layer "B.Fab")
		)
		(fp_line
			(start -0.494 -0.248)
			(end -0.494 0.25)
			(stroke
				(width 0.15)
				(type solid)
			)
			(layer "B.Fab")
		)
		(fp_line
			(start 0.504 0.25)
			(end 0.504 -0.248)
			(stroke
				(width 0.15)
				(type solid)
			)
			(layer "B.Fab")
		)
		(fp_line
			(start -0.494 0.25)
			(end 0.504 0.25)
			(stroke
				(width 0.15)
				(type solid)
			)
			(layer "B.Fab")
		)
		(pad "1" smd roundrect
			(at -0.48 0 90)
			(size 0.59 0.64)
			(layers "B.Cu" "B.Mask" "B.Paste")
			(roundrect_rratio 0.25)
			(net 1 "GND")
			(pintype "passive")
		)
		(pad "2" smd roundrect
			(at 0.48 0 90)
			(size 0.59 0.64)
			(layers "B.Cu" "B.Mask" "B.Paste")
			(roundrect_rratio 0.25)
			(net 25 "+1V35")
			(pintype "passive")
		)
	)
	(footprint "antmicro-footprints:R_0402_1005Metric"
		(layer "B.Cu")
		(at 222.1 146.2 -90)
		(descr "Resistor SMD 0402")
		(tags "resistor SMD 0402")
		(property "Reference" "R238"
			(at -3.625 -0.375 90)
			(layer "B.SilkS")
			(effects
				(font
					(size 0.7 0.7)
					(thickness 0.15)
				)
				(justify left bottom mirror)
			)
		)
		(property "Value" "R_10R_0402"
			(at 0 -1.4 90)
			(layer "B.Fab")
			(effects
				(font
					(size 0.7 0.7)
					(thickness 0.15)
				)
				(justify left bottom mirror)
			)
		)
		(property "Description" "SMD Chip Resistor, 10 ohm, ± 1%, 62.5 mW, 0402 [1005 Metric], Thick Film, General Purpose"
			(at 0 0 270)
			(layer "F.Fab")
			(hide yes)
			(effects
				(font
					(size 1.27 1.27)
					(thickness 0.15)
				)
			)
		)
		(property "Author" "Antmicro"
			(at 75.9 368.3 0)
			(layer "B.Fab")
			(hide yes)
			(effects
				(font
					(size 1 1)
					(thickness 0.15)
				)
				(justify mirror)
			)
		)
		(property "License" "Apache-2.0"
			(at 75.9 368.3 0)
			(layer "B.Fab")
			(hide yes)
			(effects
				(font
					(size 1 1)
					(thickness 0.15)
				)
				(justify mirror)
			)
		)
		(property "MPN" "CR0402-FX-10R0GLF"
			(at 75.9 368.3 0)
			(layer "B.Fab")
			(hide yes)
			(effects
				(font
					(size 1 1)
					(thickness 0.15)
				)
				(justify mirror)
			)
		)
		(property "Manufacturer" "Bourns"
			(at 75.9 368.3 0)
			(layer "B.Fab")
			(hide yes)
			(effects
				(font
					(size 1 1)
					(thickness 0.15)
				)
				(justify mirror)
			)
		)
		(property "Tolerance" "1%"
			(at 75.9 368.3 0)
			(layer "B.Fab")
			(hide yes)
			(effects
				(font
					(size 1 1)
					(thickness 0.15)
				)
				(justify mirror)
			)
		)
		(property "Val" "10R"
			(at 75.9 368.3 0)
			(layer "B.Fab")
			(hide yes)
			(effects
				(font
					(size 1 1)
					(thickness 0.15)
				)
				(justify mirror)
			)
		)
		(sheetname "HDMI + Ethernet")
		(sheetfile "hdmi-ethernet.kicad_sch")
		(attr smd)
		(fp_rect
			(start -0.925 0.47)
			(end 0.925 -0.47)
			(stroke
				(width 0.05)
				(type default)
			)
			(fill no)
			(layer "B.CrtYd")
		)
		(fp_rect
			(start -0.5 0.25)
			(end 0.5 -0.25)
			(stroke
				(width 0.15)
				(type solid)
			)
			(fill no)
			(layer "B.Fab")
		)
		(pad "1" smd roundrect
			(at -0.48 0 270)
			(size 0.59 0.64)
			(layers "B.Cu" "B.Mask" "B.Paste")
			(roundrect_rratio 0.25)
			(net 521 "/FPGA Bank 18 & 32/ETH_RMII.RXER")
			(pintype "passive")
		)
		(pad "2" smd roundrect
			(at 0.48 0 270)
			(size 0.59 0.64)
			(layers "B.Cu" "B.Mask" "B.Paste")
			(roundrect_rratio 0.25)
			(net 947 "/HDMI + Ethernet/ETH_PHY_RXER")
			(pintype "passive")
		)
	)
	(footprint "antmicro-footprints:R_0402_1005Metric"
		(layer "B.Cu")
		(at 175.33 176.2 180)
		(descr "Resistor SMD 0402")
		(tags "resistor SMD 0402")
		(property "Reference" "R280"
			(at -1.37 -2.35 0)
			(layer "B.SilkS")
			(effects
				(font
					(size 0.7 0.7)
					(thickness 0.15)
				)
				(justify left bottom mirror)
			)
		)
		(property "Value" "R_0R_0402"
			(at 0 -1.4 0)
			(layer "B.Fab")
			(effects
				(font
					(size 0.7 0.7)
					(thickness 0.15)
				)
				(justify left bottom mirror)
			)
		)
		(property "Description" "SMD Chip Resistor, Jumper, 0 ohm, 100 mW, 0402 [1005 Metric], Thick Film, General Purpose"
			(at 0 0 180)
			(layer "F.Fab")
			(hide yes)
			(effects
				(font
					(size 1.27 1.27)
					(thickness 0.15)
				)
			)
		)
		(property "Author" "Antmicro"
			(at 350.66 352.4 0)
			(layer "B.Fab")
			(hide yes)
			(effects
				(font
					(size 1 1)
					(thickness 0.15)
				)
				(justify mirror)
			)
		)
		(property "Current" "1A"
			(at 350.66 352.4 0)
			(layer "B.Fab")
			(hide yes)
			(effects
				(font
					(size 1 1)
					(thickness 0.15)
				)
				(justify mirror)
			)
		)
		(property "License" "Apache-2.0"
			(at 350.66 352.4 0)
			(layer "B.Fab")
			(hide yes)
			(effects
				(font
					(size 1 1)
					(thickness 0.15)
				)
				(justify mirror)
			)
		)
		(property "MPN" "ERJ2GE0R00X"
			(at 350.66 352.4 0)
			(layer "B.Fab")
			(hide yes)
			(effects
				(font
					(size 1 1)
					(thickness 0.15)
				)
				(justify mirror)
			)
		)
		(property "Manufacturer" "Panasonic"
			(at 350.66 352.4 0)
			(layer "B.Fab")
			(hide yes)
			(effects
				(font
					(size 1 1)
					(thickness 0.15)
				)
				(justify mirror)
			)
		)
		(property "Tolerance" ""
			(at 350.66 352.4 0)
			(layer "B.Fab")
			(hide yes)
			(effects
				(font
					(size 1 1)
					(thickness 0.15)
				)
				(justify mirror)
			)
		)
		(property "Val" "0R"
			(at 350.66 352.4 0)
			(layer "B.Fab")
			(hide yes)
			(effects
				(font
					(size 1 1)
					(thickness 0.15)
				)
				(justify mirror)
			)
		)
		(sheetname "DC-DC Converters")
		(sheetfile "dc-dc.kicad_sch")
		(attr smd)
		(fp_rect
			(start -0.925 0.47)
			(end 0.925 -0.47)
			(stroke
				(width 0.05)
				(type default)
			)
			(fill no)
			(layer "B.CrtYd")
		)
		(fp_rect
			(start -0.5 0.25)
			(end 0.5 -0.25)
			(stroke
				(width 0.15)
				(type solid)
			)
			(fill no)
			(layer "B.Fab")
		)
		(pad "1" smd roundrect
			(at -0.48 0 180)
			(size 0.59 0.64)
			(layers "B.Cu" "B.Mask" "B.Paste")
			(roundrect_rratio 0.25)
			(net 1387 "/SUP_MCU.PG_3V3")
			(pintype "passive")
		)
		(pad "2" smd roundrect
			(at 0.48 0 180)
			(size 0.59 0.64)
			(layers "B.Cu" "B.Mask" "B.Paste")
			(roundrect_rratio 0.25)
			(net 954 "/DC-DC Converters/QDCDC2_GPIO")
			(pintype "passive")
		)
	)
	(footprint "antmicro-footprints:LED_0603_1608Metric_B"
		(layer "B.Cu")
		(at 268.301 148.3 180)
		(descr "LED SMD 0603 Blue")
		(tags "LED SMD 0603 Blue")
		(property "Reference" "D11"
			(at 4.051 -0.35 0)
			(layer "B.SilkS")
			(effects
				(font
					(size 0.7 0.7)
					(thickness 0.15)
				)
				(justify left bottom mirror)
			)
		)
		(property "Value" "LED_B_0603_KP-1608QBC-D"
			(at 0 -1.6 0)
			(layer "B.Fab")
			(effects
				(font
					(size 0.7 0.7)
					(thickness 0.15)
				)
				(justify left bottom mirror)
			)
		)
		(property "Description" "LED, Blue, SMD, 0603, 20 mA, 3.3 V, 465 nm"
			(at 0 0 180)
			(layer "F.Fab")
			(hide yes)
			(effects
				(font
					(size 1.27 1.27)
					(thickness 0.15)
				)
			)
		)
		(property "Author" "Antmicro"
			(at 536.602 296.6 0)
			(layer "B.Fab")
			(hide yes)
			(effects
				(font
					(size 1 1)
					(thickness 0.15)
				)
				(justify mirror)
			)
		)
		(property "Color" "Blue"
			(at 536.602 296.6 0)
			(layer "B.Fab")
			(hide yes)
			(effects
				(font
					(size 1 1)
					(thickness 0.15)
				)
				(justify mirror)
			)
		)
		(property "License" "Apache-2.0"
			(at 536.602 296.6 0)
			(layer "B.Fab")
			(hide yes)
			(effects
				(font
					(size 1 1)
					(thickness 0.15)
				)
				(justify mirror)
			)
		)
		(property "MPN" "KP-1608QBC-D"
			(at 536.602 296.6 0)
			(layer "B.Fab")
			(hide yes)
			(effects
				(font
					(size 1 1)
					(thickness 0.15)
				)
				(justify mirror)
			)
		)
		(property "Manufacturer" "Kingbright"
			(at 536.602 296.6 0)
			(layer "B.Fab")
			(hide yes)
			(effects
				(font
					(size 1 1)
					(thickness 0.15)
				)
				(justify mirror)
			)
		)
		(property "Public" "False"
			(at 536.602 296.6 0)
			(layer "B.Fab")
			(hide yes)
			(effects
				(font
					(size 1 1)
					(thickness 0.15)
				)
				(justify mirror)
			)
		)
		(sheetname "Power supply")
		(sheetfile "power-supply.kicad_sch")
		(attr smd)
		(fp_line
			(start 0.22 0.35)
			(end -0.22 0.35)
			(stroke
				(width 0.15)
				(type solid)
			)
			(layer "B.SilkS")
		)
		(fp_line
			(start 0.22 -0.35)
			(end -0.22 -0.35)
			(stroke
				(width 0.15)
				(type solid)
			)
			(layer "B.SilkS")
		)
		(fp_line
			(start 0.105328 -0.001008)
			(end 0.24 -0.001)
			(stroke
				(width 0.1)
				(type solid)
			)
			(layer "B.SilkS")
		)
		(fp_line
			(start 0.105328 -0.201008)
			(end 0.105328 0.198992)
			(stroke
				(width 0.1)
				(type solid)
			)
			(layer "B.SilkS")
		)
		(fp_line
			(start 0.105328 -0.201008)
			(end -0.094672 -0.001008)
			(stroke
				(width 0.1)
				(type solid)
			)
			(layer "B.SilkS")
		)
		(fp_line
			(start -0.094672 -0.001008)
			(end 0.105328 0.198992)
			(stroke
				(width 0.1)
				(type solid)
			)
			(layer "B.SilkS")
		)
		(fp_line
			(start -0.094672 -0.001008)
			(end -0.24 -0.001008)
			(stroke
				(width 0.1)
				(type solid)
			)
			(layer "B.SilkS")
		)
		(fp_line
			(start -0.094672 -0.201008)
			(end -0.094672 0.198992)
			(stroke
				(width 0.1)
				(type solid)
			)
			(layer "B.SilkS")
		)
		(fp_line
			(start -1.18 0.319)
			(end -1.18 -0.321)
			(stroke
				(width 0.15)
				(type solid)
			)
			(layer "B.SilkS")
		)
		(fp_rect
			(start 1.25 -0.65)
			(end -1.25 0.65)
			(stroke
				(width 0.05)
				(type solid)
			)
			(fill no)
			(layer "B.CrtYd")
		)
		(fp_line
			(start 0.599 0)
			(end 0.201 0)
			(stroke
				(width 0.15)
				(type solid)
			)
			(layer "B.Fab")
		)
		(fp_line
			(start 0.201 0.202)
			(end -0.101 0)
			(stroke
				(width 0.15)
				(type solid)
			)
			(layer "B.Fab")
		)
		(fp_line
			(start 0.201 0)
			(end 0.201 0.202)
			(stroke
				(width 0.15)
				(type solid)
			)
			(layer "B.Fab")
		)
		(fp_line
			(start 0.201 -0.2)
			(end 0.201 0)
			(stroke
				(width 0.15)
				(type solid)
			)
			(layer "B.Fab")
		)
		(fp_line
			(start -0.101 0)
			(end 0.201 -0.2)
			(stroke
				(width 0.15)
				(type solid)
			)
			(layer "B.Fab")
		)
		(fp_line
			(start -0.199 0.202)
			(end -0.199 -0.1)
			(stroke
				(width 0.15)
				(type solid)
			)
			(layer "B.Fab")
		)
		(fp_line
			(start -0.199 0)
			(end -0.597 0)
			(stroke
				(width 0.15)
				(type solid)
			)
			(layer "B.Fab")
		)
		(fp_line
			(start -0.199 -0.2)
			(end -0.199 -0.1)
			(stroke
				(width 0.15)
				(type solid)
			)
			(layer "B.Fab")
		)
		(fp_rect
			(start 0.848 -0.4)
			(end -0.85 0.402)
			(stroke
				(width 0.15)
				(type solid)
			)
			(fill no)
			(layer "B.Fab")
		)
		(pad "1" smd roundrect
			(at -0.7 0)
			(size 0.8 1)
			(layers "B.Cu" "B.Mask" "B.Paste")
			(roundrect_rratio 0.2)
			(net 769 "/Power supply/PD_PWR_OK2")
			(pinfunction "C")
			(pintype "passive")
		)
		(pad "2" smd roundrect
			(at 0.7 0)
			(size 0.8 1)
			(layers "B.Cu" "B.Mask" "B.Paste")
			(roundrect_rratio 0.2)
			(net 19 "Net-(D11-A)")
			(pinfunction "A")
			(pintype "passive")
		)
	)
	(footprint "antmicro-footprints:C_0402_1005Metric"
		(layer "B.Cu")
		(at 202.5 144 90)
		(descr "Capacitor SMD 0402")
		(tags "capacitor SMD 0402")
		(property "Reference" "C89"
			(at 1.15 1.2 270)
			(layer "B.SilkS")
			(effects
				(font
					(size 0.7 0.7)
					(thickness 0.15)
				)
				(justify left bottom mirror)
			)
		)
		(property "Value" "C_100n_0402"
			(at 0 -1.169 270)
			(layer "B.Fab")
			(effects
				(font
					(size 0.7 0.7)
					(thickness 0.15)
				)
				(justify left bottom mirror)
			)
		)
		(property "Description" "SMD Multilayer Ceramic Capacitor, 0.1 µF, 50 V, 0402 [1005 Metric], ± 10%, X5R, GRM Series"
			(at 0 0 90)
			(layer "F.Fab")
			(hide yes)
			(effects
				(font
					(size 1.27 1.27)
					(thickness 0.15)
				)
			)
		)
		(property "Author" "Antmicro"
			(at 346.5 -58.5 0)
			(layer "B.Fab")
			(hide yes)
			(effects
				(font
					(size 1 1)
					(thickness 0.15)
				)
				(justify mirror)
			)
		)
		(property "Dielectric" "X5R"
			(at 346.5 -58.5 0)
			(layer "B.Fab")
			(hide yes)
			(effects
				(font
					(size 1 1)
					(thickness 0.15)
				)
				(justify mirror)
			)
		)
		(property "License" "Apache-2.0"
			(at 346.5 -58.5 0)
			(layer "B.Fab")
			(hide yes)
			(effects
				(font
					(size 1 1)
					(thickness 0.15)
				)
				(justify mirror)
			)
		)
		(property "MPN" "GRM155R61H104KE14D"
			(at 346.5 -58.5 0)
			(layer "B.Fab")
			(hide yes)
			(effects
				(font
					(size 1 1)
					(thickness 0.15)
				)
				(justify mirror)
			)
		)
		(property "Manufacturer" "Murata"
			(at 346.5 -58.5 0)
			(layer "B.Fab")
			(hide yes)
			(effects
				(font
					(size 1 1)
					(thickness 0.15)
				)
				(justify mirror)
			)
		)
		(property "Val" "100n"
			(at 346.5 -58.5 0)
			(layer "B.Fab")
			(hide yes)
			(effects
				(font
					(size 1 1)
					(thickness 0.15)
				)
				(justify mirror)
			)
		)
		(property "Voltage" "50V"
			(at 346.5 -58.5 0)
			(layer "B.Fab")
			(hide yes)
			(effects
				(font
					(size 1 1)
					(thickness 0.15)
				)
				(justify mirror)
			)
		)
		(sheetname "FPGA Bank 18 & 32")
		(sheetfile "fpga-bank-18-32.kicad_sch")
		(attr smd)
		(fp_rect
			(start -0.925 0.47)
			(end 0.925 -0.47)
			(stroke
				(width 0.05)
				(type default)
			)
			(fill no)
			(layer "B.CrtYd")
		)
		(fp_line
			(start 0.504 -0.248)
			(end -0.494 -0.248)
			(stroke
				(width 0.15)
				(type solid)
			)
			(layer "B.Fab")
		)
		(fp_line
			(start -0.494 -0.248)
			(end -0.494 0.25)
			(stroke
				(width 0.15)
				(type solid)
			)
			(layer "B.Fab")
		)
		(fp_line
			(start 0.504 0.25)
			(end 0.504 -0.248)
			(stroke
				(width 0.15)
				(type solid)
			)
			(layer "B.Fab")
		)
		(fp_line
			(start -0.494 0.25)
			(end 0.504 0.25)
			(stroke
				(width 0.15)
				(type solid)
			)
			(layer "B.Fab")
		)
		(pad "1" smd roundrect
			(at -0.48 0 90)
			(size 0.59 0.64)
			(layers "B.Cu" "B.Mask" "B.Paste")
			(roundrect_rratio 0.25)
			(net 1 "GND")
			(pintype "passive")
		)
		(pad "2" smd roundrect
			(at 0.48 0 90)
			(size 0.59 0.64)
			(layers "B.Cu" "B.Mask" "B.Paste")
			(roundrect_rratio 0.25)
			(net 26 "+1V8")
			(pintype "passive")
		)
	)
	(footprint "antmicro-footprints:R_0402_1005Metric"
		(layer "B.Cu")
		(at 163.900001 90.760001)
		(descr "Resistor SMD 0402")
		(tags "resistor SMD 0402")
		(property "Reference" "R265"
			(at -0.775001 0.389999 180)
			(layer "B.SilkS")
			(effects
				(font
					(size 0.7 0.7)
					(thickness 0.15)
				)
				(justify left bottom mirror)
			)
		)
		(property "Value" "R_10k_0402"
			(at 0 -1.4 180)
			(layer "B.Fab")
			(effects
				(font
					(size 0.7 0.7)
					(thickness 0.15)
				)
				(justify left bottom mirror)
			)
		)
		(property "Description" "SMD Chip Resistor, 10 kohm, ± 1%, 62.5 mW, 0402 [1005 Metric], Thick Film, General Purpose"
			(at 0 0 0)
			(layer "F.Fab")
			(hide yes)
			(effects
				(font
					(size 1.27 1.27)
					(thickness 0.15)
				)
			)
		)
		(property "Author" "Antmicro"
			(at 0 0 0)
			(layer "B.Fab")
			(hide yes)
			(effects
				(font
					(size 1 1)
					(thickness 0.15)
				)
				(justify mirror)
			)
		)
		(property "License" "Apache-2.0"
			(at 0 0 0)
			(layer "B.Fab")
			(hide yes)
			(effects
				(font
					(size 1 1)
					(thickness 0.15)
				)
				(justify mirror)
			)
		)
		(property "MPN" "CR0402-FX-1002GLF"
			(at 0 0 0)
			(layer "B.Fab")
			(hide yes)
			(effects
				(font
					(size 1 1)
					(thickness 0.15)
				)
				(justify mirror)
			)
		)
		(property "Manufacturer" "Bourns"
			(at 0 0 0)
			(layer "B.Fab")
			(hide yes)
			(effects
				(font
					(size 1 1)
					(thickness 0.15)
				)
				(justify mirror)
			)
		)
		(property "Tolerance" "1%"
			(at 0 0 0)
			(layer "B.Fab")
			(hide yes)
			(effects
				(font
					(size 1 1)
					(thickness 0.15)
				)
				(justify mirror)
			)
		)
		(property "Val" "10k"
			(at 0 0 0)
			(layer "B.Fab")
			(hide yes)
			(effects
				(font
					(size 1 1)
					(thickness 0.15)
				)
				(justify mirror)
			)
		)
		(sheetname "FMC+ HSPC")
		(sheetfile "fmc-hspc.kicad_sch")
		(attr smd)
		(fp_rect
			(start -0.925 0.47)
			(end 0.925 -0.47)
			(stroke
				(width 0.05)
				(type default)
			)
			(fill no)
			(layer "B.CrtYd")
		)
		(fp_rect
			(start -0.5 0.25)
			(end 0.5 -0.25)
			(stroke
				(width 0.15)
				(type solid)
			)
			(fill no)
			(layer "B.Fab")
		)
		(pad "1" smd roundrect
			(at -0.48 0)
			(size 0.59 0.64)
			(layers "B.Cu" "B.Mask" "B.Paste")
			(roundrect_rratio 0.25)
			(net 695 "/FMC+ HSPC/FMC.~{PERST}")
			(pintype "passive")
		)
		(pad "2" smd roundrect
			(at 0.48 0)
			(size 0.59 0.64)
			(layers "B.Cu" "B.Mask" "B.Paste")
			(roundrect_rratio 0.25)
			(net 24 "+3V3")
			(pintype "passive")
		)
	)
)
